FILE_TYPE=LIBRARY_PARTS;
primitive 'CONN4_H73295001','CONN4_H73295001_PIP';
  pin
    'IO1':
      PIN_NUMBER='(1)';
      BIDIRECTIONAL='TRUE';
      INPUT_LOAD='(-0.01,0.01)';
      OUTPUT_LOAD='(1.0,-1.0)';
    'IO2':
      PIN_NUMBER='(2)';
      BIDIRECTIONAL='TRUE';
      INPUT_LOAD='(-0.01,0.01)';
      OUTPUT_LOAD='(1.0,-1.0)';
    'IO3':
      PIN_NUMBER='(3)';
      BIDIRECTIONAL='TRUE';
      INPUT_LOAD='(-0.01,0.01)';
      OUTPUT_LOAD='(1.0,-1.0)';
    'IO4':
      PIN_NUMBER='(4)';
      BIDIRECTIONAL='TRUE';
      INPUT_LOAD='(-0.01,0.01)';
      OUTPUT_LOAD='(1.0,-1.0)';
  end_pin;
  body
    PART_NAME='CONN4_H73295001';
    PHYS_DES_PREFIX='J';
  end_body;
end_primitive;

END.
